# S9S_MB_2U (Grand Teton) — schematic netlist excerpt (pin names and nets, part order shuffled) for the footprints in the layout excerpt that follows; sources: Cadence DE-HDL packaged netlist, KiCad conversion of 03242023_DA0F0TMBIJ0_F0T_Motherboard_J_brd_V01_OCP.brd

R4647  Q_RES  1K 1% CHIP  pkg 0402LF  page 167 : A = FM_P2E_BUF2_VODA_DB ; B = GND
R4072  Q_RES  10K 1% CHIP  pkg 0402LF  page 192 : A = P12V_AUX ; B = P3V3_E1S_0_EN_G

(kicad_pcb
	(version 20260206)
	(generator "pcbnew")
	(generator_version "10.0")
	(general
		(thickness 1.6)
		(legacy_teardrops no)
	)
	(paper "A4")
	(title_block
		(title "03242023_DA0F0TMBIJ0_F0T_Motherboard_J_brd_V01_OCP.brd")
		(comment 1 "Grand Teton / footprints 494-495 of 6105")
	)
	(layers
		(0 "F.Cu" signal "TOP")
		(4 "In1.Cu" signal "GND")
		(6 "In2.Cu" signal "IN1")
		(8 "In3.Cu" signal "GND1")
		(10 "In4.Cu" signal "IN2")
		(12 "In5.Cu" signal "GND2")
		(14 "In6.Cu" signal "IN3")
		(16 "In7.Cu" signal "GND3")
		(18 "In8.Cu" signal "VCC")
		(20 "In9.Cu" signal "VCC1")
		(22 "In10.Cu" signal "GND4")
		(24 "In11.Cu" signal "IN4")
		(26 "In12.Cu" signal "GND5")
		(28 "In13.Cu" signal "IN5")
		(30 "In14.Cu" signal "GND6")
		(32 "In15.Cu" signal "IN6")
		(34 "In16.Cu" signal "GND7")
		(2 "B.Cu" signal "BOTTOM")
		(9 "F.Adhes" user "F.Adhesive")
		(11 "B.Adhes" user "B.Adhesive")
		(13 "F.Paste" user "Package Geometry/Pastemask Top")
		(15 "B.Paste" user "Package Geometry/Pastemask Bottom")
		(5 "F.SilkS" user "Ref Des/Silkscreen Top")
		(7 "B.SilkS" user "Ref Des/Silkscreen Bottom")
		(1 "F.Mask" user "Board Geometry/Soldermask Top")
		(3 "B.Mask" user "Board Geometry/Soldermask Bottom")
		(17 "Dwgs.User" user "User.Drawings")
		(19 "Cmts.User" user "User.Comments")
		(21 "Eco1.User" user "User.Eco1")
		(23 "Eco2.User" user "User.Eco2")
		(25 "Edge.Cuts" user "Board Geometry/Outline")
		(27 "Margin" user)
		(31 "F.CrtYd" user "Package Geometry/Place Bound Top")
		(29 "B.CrtYd" user "Package Geometry/Place Bound Bottom")
		(35 "F.Fab" user "Ref Des/Assembly Top")
		(33 "B.Fab" user "Ref Des/Assembly Bottom")
	)
	(footprint ""
		(layer "F.Cu")
		(at 294.39108 -53.68798 180)
		(property "Reference" "R4072"
			(at 0 0 180)
			(layer "F.SilkS")
			(hide yes)
			(effects
				(font
					(size 1.27 1.27)
				)
			)
		)
		(property "Value" ""
			(at 0 0 180)
			(layer "F.Fab")
			(effects
				(font
					(size 1.27 1.27)
				)
			)
		)
		(duplicate_pad_numbers_are_jumpers no)
		(fp_line
			(start 0.7874 0.4064)
			(end -0.7874 0.4064)
			(stroke
				(width 0.1524)
				(type default)
			)
			(layer "F.SilkS")
		)
		(fp_line
			(start 0.7874 -0.4064)
			(end 0.7874 0.4064)
			(stroke
				(width 0.1524)
				(type default)
			)
			(layer "F.SilkS")
		)
		(fp_line
			(start -0.7874 0.4064)
			(end -0.7874 -0.4064)
			(stroke
				(width 0.1524)
				(type default)
			)
			(layer "F.SilkS")
		)
		(fp_line
			(start -0.7874 -0.4064)
			(end 0.7874 -0.4064)
			(stroke
				(width 0.1524)
				(type default)
			)
			(layer "F.SilkS")
		)
		(fp_line
			(start 0.67945 0.3048)
			(end 0.120396 0.3048)
			(stroke
				(width 0.1)
				(type default)
			)
			(layer "F.Fab")
		)
		(fp_line
			(start 0.67945 -0.3048)
			(end 0.67945 0.3048)
			(stroke
				(width 0.1)
				(type default)
			)
			(layer "F.Fab")
		)
		(fp_line
			(start 0.12065 -0.2794)
			(end 0.12065 -0.3048)
			(stroke
				(width 0.1)
				(type default)
			)
			(layer "F.Fab")
		)
		(fp_line
			(start 0.12065 -0.3048)
			(end 0.67945 -0.3048)
			(stroke
				(width 0.1)
				(type default)
			)
			(layer "F.Fab")
		)
		(fp_line
			(start 0.120396 0.3048)
			(end 0.120396 0.2794)
			(stroke
				(width 0.1)
				(type default)
			)
			(layer "F.Fab")
		)
		(fp_line
			(start 0.120396 0.2794)
			(end -0.12065 0.2794)
			(stroke
				(width 0.1)
				(type default)
			)
			(layer "F.Fab")
		)
		(fp_line
			(start -0.12065 0.3048)
			(end -0.67945 0.3048)
			(stroke
				(width 0.1)
				(type default)
			)
			(layer "F.Fab")
		)
		(fp_line
			(start -0.12065 0.2794)
			(end -0.12065 0.3048)
			(stroke
				(width 0.1)
				(type default)
			)
			(layer "F.Fab")
		)
		(fp_line
			(start -0.12065 -0.2794)
			(end 0.12065 -0.2794)
			(stroke
				(width 0.1)
				(type default)
			)
			(layer "F.Fab")
		)
		(fp_line
			(start -0.12065 -0.305054)
			(end -0.12065 -0.2794)
			(stroke
				(width 0.1)
				(type default)
			)
			(layer "F.Fab")
		)
		(fp_line
			(start -0.67945 0.3048)
			(end -0.67945 -0.305054)
			(stroke
				(width 0.1)
				(type default)
			)
			(layer "F.Fab")
		)
		(fp_line
			(start -0.67945 -0.305054)
			(end -0.12065 -0.305054)
			(stroke
				(width 0.1)
				(type default)
			)
			(layer "F.Fab")
		)
		(pad "1" smd circle
			(at -0.40005 0 180)
			(size 0 0)
			(layers "F.Cu" "F.Mask" "F.Paste")
			(net "P12V_AUX")
		)
		(pad "2" smd circle
			(at 0.40005 0 180)
			(size 0 0)
			(layers "F.Cu" "F.Mask" "F.Paste")
			(net "P3V3_E1S_0_EN_G")
		)
	)
	(footprint ""
		(layer "F.Cu")
		(at 46.087792 -393.315444)
		(property "Reference" "R4647"
			(at 0 0 0)
			(layer "F.SilkS")
			(hide yes)
			(effects
				(font
					(size 1.27 1.27)
				)
			)
		)
		(property "Value" ""
			(at 0 0 0)
			(layer "F.Fab")
			(effects
				(font
					(size 1.27 1.27)
				)
			)
		)
		(duplicate_pad_numbers_are_jumpers no)
		(fp_line
			(start -0.7874 -0.4064)
			(end 0.7874 -0.4064)
			(stroke
				(width 0.1524)
				(type default)
			)
			(layer "F.SilkS")
		)
		(fp_line
			(start -0.7874 0.4064)
			(end -0.7874 -0.4064)
			(stroke
				(width 0.1524)
				(type default)
			)
			(layer "F.SilkS")
		)
		(fp_line
			(start 0.7874 -0.4064)
			(end 0.7874 0.4064)
			(stroke
				(width 0.1524)
				(type default)
			)
			(layer "F.SilkS")
		)
		(fp_line
			(start 0.7874 0.4064)
			(end -0.7874 0.4064)
			(stroke
				(width 0.1524)
				(type default)
			)
			(layer "F.SilkS")
		)
		(fp_line
			(start -0.67945 -0.305054)
			(end -0.12065 -0.305054)
			(stroke
				(width 0.1)
				(type default)
			)
			(layer "F.Fab")
		)
		(fp_line
			(start -0.67945 0.3048)
			(end -0.67945 -0.305054)
			(stroke
				(width 0.1)
				(type default)
			)
			(layer "F.Fab")
		)
		(fp_line
			(start -0.12065 -0.305054)
			(end -0.12065 -0.2794)
			(stroke
				(width 0.1)
				(type default)
			)
			(layer "F.Fab")
		)
		(fp_line
			(start -0.12065 -0.2794)
			(end 0.12065 -0.2794)
			(stroke
				(width 0.1)
				(type default)
			)
			(layer "F.Fab")
		)
		(fp_line
			(start -0.12065 0.2794)
			(end -0.12065 0.3048)
			(stroke
				(width 0.1)
				(type default)
			)
			(layer "F.Fab")
		)
		(fp_line
			(start -0.12065 0.3048)
			(end -0.67945 0.3048)
			(stroke
				(width 0.1)
				(type default)
			)
			(layer "F.Fab")
		)
		(fp_line
			(start 0.120396 0.2794)
			(end -0.12065 0.2794)
			(stroke
				(width 0.1)
				(type default)
			)
			(layer "F.Fab")
		)
		(fp_line
			(start 0.120396 0.3048)
			(end 0.120396 0.2794)
			(stroke
				(width 0.1)
				(type default)
			)
			(layer "F.Fab")
		)
		(fp_line
			(start 0.12065 -0.3048)
			(end 0.67945 -0.3048)
			(stroke
				(width 0.1)
				(type default)
			)
			(layer "F.Fab")
		)
		(fp_line
			(start 0.12065 -0.2794)
			(end 0.12065 -0.3048)
			(stroke
				(width 0.1)
				(type default)
			)
			(layer "F.Fab")
		)
		(fp_line
			(start 0.67945 -0.3048)
			(end 0.67945 0.3048)
			(stroke
				(width 0.1)
				(type default)
			)
			(layer "F.Fab")
		)
		(fp_line
			(start 0.67945 0.3048)
			(end 0.120396 0.3048)
			(stroke
				(width 0.1)
				(type default)
			)
			(layer "F.Fab")
		)
		(pad "1" smd circle
			(at -0.40005 0)
			(size 0 0)
			(layers "F.Cu" "F.Mask" "F.Paste")
			(net "FM_P2E_BUF2_VODA_DB")
		)
		(pad "2" smd circle
			(at 0.40005 0)
			(size 0 0)
			(layers "F.Cu" "F.Mask" "F.Paste")
			(net "GND")
		)
	)
)
